# BASEBOARD_FAB2 (Tioga Pass) — schematic parts with pin connectivity, parts 1335–1499 of 4751; source: Cadence DE-HDL packaged netlist (pstxprt.dat, pstxnet.dat, pstchip.dat)

C6P9  CAP_A  0.1UF 16V 10% X7R  pkg 0402V  page 102 : 1 = P3V3_DB1200 ; 2 = GND
C6P10  CAP_A  0.1UF 16V 10% X7R  pkg 0402V  page 102 : 1 = P3V3_DB1200 ; 2 = GND
C6P11  CAP_A  0.1UF 16V 10% X7R  pkg 0402V  page 102 : 1 = P3V3_DB1200 ; 2 = GND
C6P12  CAP_A  0.1UF 16V 10% X7R  pkg 0402V  page 102 : 1 = P3V3_DB1200 ; 2 = GND
C6P13  CAP  10UF 16V 10% X6S  pkg 0805  page 202 : 1 = VR_FET_SW_P12V_STBY_PVCCIN_CPU0 ; 2 = GND
C6P14  CAPP  470UF 2.5V 20% ALUM  pkg 3018  page 203 : 1 = PVCCIN_CPU0 ; 2 = GND
C6P15  CAP  10UF 16V 10% X6S  pkg 0805  page 203 : 1 = VR_FET_SW_P12V_STBY_PVCCIN_CPU0 ; 2 = GND
C6P16  CAP_A  22.0UF 4V 20% X6S  pkg 0603V  page 202 : 1 = PVCCIN_CPU0 ; 2 = GND
C6P17  CAP  10UF 16V 10% X6S  pkg 0805  page 204 : 1 = VR_FET_SW_P12V_STBY_PVCCIN_CPU0 ; 2 = GND
C6P18  CAPP  470UF 2.5V 20% ALUM  pkg 3018  page 203 : 1 = PVCCIN_CPU0 ; 2 = GND
C6P19  CAP  10UF 16V 10% X6S  pkg 0805  page 203 : 1 = VR_FET_SW_P12V_STBY_PVCCIN_CPU0 ; 2 = GND
C6P20  CAP  10UF 16V 10% X6S  pkg 0805  page 203 : 1 = VR_FET_SW_P12V_STBY_PVCCIN_CPU0 ; 2 = GND
C6P21  CAP_A  22.0UF 4V 20% X6S  pkg 0603V  page 203 : 1 = PVCCIN_CPU0 ; 2 = GND
C6P22  CAP  10UF 16V 10% X6S  pkg 0805  page 202 : 1 = VR_FET_SW_P12V_STBY_PVCCIN_CPU0 ; 2 = GND
C6P23  CAPP  470UF 2.5V 20% ALUM  pkg 3018  page 203 : 1 = PVCCIN_CPU0 ; 2 = GND
C6P24  CAP  10UF 16V 10% X6S  pkg 0805  page 203 : 1 = VR_FET_SW_P12V_STBY_PVCCIN_CPU0 ; 2 = GND
C6R2  CAP_A  22.0UF 4V 20% X6S  pkg 0603V  page 204 : 1 = PVCCIN_CPU0 ; 2 = GND
C6R3  CAPP  470UF 2.5V 20% ALUM  pkg 3018  page 203 : 1 = PVCCIN_CPU0 ; 2 = GND
C6R4  CAP  10UF 16V 10% X6S  pkg 0805  page 202 : 1 = VR_FET_SW_P12V_STBY_PVCCIN_CPU0 ; 2 = GND
C6R5  CAPP  470UF 2.5V 20% ALUM  pkg 3018  page 214 : 1 = PVCCIO_CPU1 ; 2 = GND
C6R6  CAP  10UF 16V 10% X6S  pkg 0805  page 203 : 1 = VR_FET_SW_P12V_STBY_PVCCIN_CPU0 ; 2 = GND
C6R7  CAP_A  22.0UF 4V 20% X6S  pkg 0603V  page 202 : 1 = PVCCIN_CPU0 ; 2 = GND
C6R8  CAP  10UF 16V 10% X6S  pkg 0805  page 214 : 1 = VR_FET_SW_P12V_STBY_PVCCIN_CPU0 ; 2 = GND
C6R9  CAPP  470UF 2.5V 20% ALUM  pkg 3018  page 203 : 1 = PVCCIN_CPU0 ; 2 = GND
C6R10  CAP  10UF 16V 10% X6S  pkg 0805  page 214 : 1 = VR_FET_SW_P12V_STBY_PVCCIN_CPU0 ; 2 = GND
C6R11  CAP  10UF 16V 10% X6S  pkg 0805  page 202 : 1 = VR_FET_SW_P12V_STBY_PVCCIN_CPU0 ; 2 = GND
C6R12  CAPP  470UF 2.5V 20% ALUM  pkg 3018  page 214 : 1 = PVCCIO_CPU1 ; 2 = GND
C6R13  CAP  10UF 16V 10% X6S  pkg 0805  page 202 : 1 = VR_FET_SW_P12V_STBY_PVCCIN_CPU0 ; 2 = GND
C6R14  CAP  10UF 16V 10% X6S  pkg 0805  page 214 : 1 = VR_FET_SW_P12V_STBY_PVCCIN_CPU0 ; 2 = GND
C6R16  CAPP  470UF 2.5V 20% ALUM  pkg 3018  page 193 : 1 = PVCCMCP_CPU1 ; 2 = GND
C6T1  CAP_A  0.01UF 25V 10% X7R  pkg 0402V  page 44 : 1 = M_A_VREF ; 2 = GND
C6T2  CAP  10UF 16V 10% X7R  pkg 0805  page 197 : 1 = P12V_NVDIMM_ABC ; 2 = GND
C6U2  CAP  47UF 4V 20% X6S  pkg 0805  page 233 : 1 = PVPP_GHJ ; 2 = GND
C6U3  CAP  47UF 4V 20% X6S  pkg 0805  page 233 : 1 = PVPP_GHJ ; 2 = GND
C6U4  CAP  10UF 16V 10% X6S  pkg 0805  page 233 : 1 = VR_FET_SW_P12V_STBY_PVPP_GHJ ; 2 = GND
C6U5  CAP_A  0.1UF 16V 10% X7R  pkg 0402V  page 233 : 1 = VR_FET_SW_P12V_STBY_PVPP_GHJ ; 2 = GND
C6U6  CAP  4.7UF 6.3V 10% X6S  pkg 0603  page 233 : 1 = VR_VB_PVPP_GHJ ; 2 = AGND_PVPP_GHJ
C6U7  CAP  10UF 16V 10% X6S  pkg 0805  page 233 : 1 = VR_FET_SW_P12V_STBY_PVPP_GHJ ; 2 = GND
C6U8  CAP  10UF 16V 10% X6S  pkg 0805  page 233 : 1 = VR_FET_SW_P12V_STBY_PVPP_GHJ ; 2 = GND
C6U9  CAP_A  0.01UF 25V 10% X7R  pkg 0402V  page 46 : 1 = M_B_VREF ; 2 = GND
C6U10  CAP  10UF 16V 10% X7R  pkg 0805  page 197 : 1 = P12V_NVDIMM_ABC ; 2 = GND
C6U11  CAP  4.7UF 6.3V 10% X6S  pkg 0603  page 229 : 1 = VSENSE_PVDDQ_GHJ_VTT ; 2 = GND
C6U12  CAP  4.7UF 6.3V 10% X6S  pkg 0603  page 221 : 1 = VSENSE_PVDDQ_ABC_VTT ; 2 = GND
C6U13  CAP  10UF 4V 20% X6S  pkg 0603LF  page 229 : 1 = PVDDQ_GHJ ; 2 = GND
C6U14  CAP  10UF 4V 20% X6S  pkg 0603LF  page 229 : 1 = PVDDQ_GHJ ; 2 = GND
C6U15  CAP  10UF 4V 20% X6S  pkg 0603LF  page 221 : 1 = PVDDQ_ABC ; 2 = GND
C6U16  CAP  10UF 4V 20% X6S  pkg 0603LF  page 221 : 1 = PVDDQ_ABC ; 2 = GND
C6U17  CAP_A  0.01UF 25V 10% X7R  pkg 0402V  page 48 : 1 = M_C_VREF ; 2 = GND
C6U18  CAP  10UF 16V 10% X7R  pkg 0805  page 197 : 1 = P12V_NVDIMM_ABC ; 2 = GND
C6W1  CAP_A  0.1UF 16V 10% X7R  pkg 0402V  page 247 : 1 = P3V3_STBY ; 2 = GND
C6W2  CAP_A  0.1UF 16V 10% X7R  pkg 0402V  page 247 : 1 = P3V3_STBY ; 2 = GND
C6W3  CAP_A  0.1UF 16V 10% X7R  pkg 0402V  page 247 : 1 = P3V3_STBY ; 2 = GND
C6W4  CAP_A  0.1UF 16V 10% X7R  pkg 0402V  page 247 : 1 = P3V3_STBY ; 2 = GND
C6W10  CAP_A  0.1UF 16V 10% X7R  pkg 0402V  page 176 : 1 = P3V3_STBY ; 2 = GND
C6W11  CAP  100UF 4V 20% X5R  pkg 0805  page 221 : 1 = PVTT_ABC ; 2 = GND
C6W12  CAP  100UF 4V 20% X5R  pkg 0805  page 229 : 1 = PVTT_GHJ ; 2 = GND
C6W13  CAP  100UF 4V 20% X5R  pkg 0805  page 230 : 1 = PVTT_KLM ; 2 = GND
C6W14  CAP_A  0.1UF 16V 10% X7R  pkg 0402V  page 164 : 1 = P3V3_STBY ; 2 = GND
C7A5  CAP_A  0.1UF 16V 10% X7R  pkg 0402V  page 219 : 1 = VR_FET_SW_P12V_STBY_PVDDQ_DEF ; 2 = GND
C7A6  CAP  1.0UF 16V 10% X6S  pkg 0402  page 236 : 1 = VR_PVNN_PCH_PH1_VCIN ; 2 = GND
C7A7  CAP  1.0UF 16V 10% X6S  pkg 0402  page 236 : 1 = VR_FET_SW_P12V_STBY_PVDDQ_DEF ; 2 = GND
C7A8  CAP  0.22UF 16V 10% X7R  pkg 0402  page 236 : 1 = P5V_STBY ; 2 = GND
C7A9  CAP  1.0UF 16V 10% X6S  pkg 0402  page 236 : 1 = VR_FET_SW_P12V_STBY_PVDDQ_DEF ; 2 = GND
C7A10  CAP  1.0UF 16V 10% X6S  pkg 0402  page 236 : 1 = VR_P1V05_PCH_STBY_PH1_VCIN ; 2 = GND
C7A11  CAP  1.0UF 16V 10% X6S  pkg 0402  page 219 : 1 = VR_FET_SW_P12V_STBY_PVDDQ_DEF ; 2 = GND
C7A12  CAP  0.220UF 16V 10% X7R  pkg 0402  page 219 : 1 = VR_PVDDQ_DEF_PH1_BOOT ; 2 = VR_PVDDQ_DEF_PH1_PHASE
C7A13  SC22U16V5MX-4-GP  20%  pkg SMD-BCG5  page 236 : 1 = VR_FET_SW_P12V_STBY_PVDDQ_DEF ; 2 = GND
C7A14  SC22U16V5MX-4-GP  20%  pkg SMD-BCG5  page 236 : 1 = VR_FET_SW_P12V_STBY_PVDDQ_DEF ; 2 = GND
C7A16  CAP  1.0UF 16V 10% X6S  pkg 0402  page 219 : 1 = VR_PVDDQ_DEF_PH1_VCIN ; 2 = GND
C7A17  CAP  0.22UF 16V 10% X7R  pkg 0402  page 219 : 1 = P5V_STBY ; 2 = GND
C7A18  SC1U10V2KX-4-GP  10%  pkg SMD-BCG6  page 219 : 1 = P5V_STBY ; 2 = GND
C7A20  CAP_A  0.1UF 16V 10% X7R  pkg 0402V  page 219 : 1 = VR_FET_SW_P12V_STBY_PVDDQ_DEF ; 2 = GND
C7A21  CAP  1.0UF 16V 10% X6S  pkg 0402  page 219 : 1 = VR_FET_SW_P12V_STBY_PVDDQ_DEF ; 2 = GND
C7A22  CAP  0.220UF 16V 10% X7R  pkg 0402  page 219 : 1 = VR_PVDDQ_DEF_PH2_BOOT ; 2 = VR_PVDDQ_DEF_PH2_PHASE
C7A24  CAP  1.0UF 16V 10% X6S  pkg 0402  page 219 : 1 = VR_PVDDQ_DEF_PH2_VCIN ; 2 = GND
C7A25  CAP  0.22UF 16V 10% X7R  pkg 0402  page 219 : 1 = P5V_STBY ; 2 = GND
C7A26  SC1U10V2KX-4-GP  10%  pkg SMD-BCG6  page 219 : 1 = P5V_STBY ; 2 = GND
C7A27  CAPP  470UF 2V 20% ALUM  pkg SM  page 236 : 1 = PVNN_PCH_STBY ; 2 = GND
C7A28  CAP  220PF 50V 10% X7R  pkg 0402LF  page 218 : 1 = VR_PVDDQ_DEF_AVSP ; 2 = VSENSE_PVDDQ_DEF_N
C7A29  CAP  220PF 50V 10% X7R  pkg 0402LF  page 218 : 1 = A_TSENSE_PVDDQ_DEF ; 2 = GND
C7A30  CAP  22UF 4V 20% X6S  pkg 0805LF  page 236 : 1 = PVNN_PCH_STBY ; 2 = GND
C7A31  CAP  47UF 4V 20% X6S  pkg 0805  page 132 : 1 = PVNN_PCH_STBY ; 2 = GND
C7A32  CAP  47UF 4V 20% X6S  pkg 0805  page 132 : 1 = PVNN_PCH_STBY ; 2 = GND
C7A33  CAP  47UF 4V 20% X6S  pkg 0805  page 132 : 1 = PVNN_PCH_STBY ; 2 = GND
C7A34  CAP  3300PF 50V 10% EMPTY  pkg 0402LF  page 232 : 1 = VR_PVPP_DEF_PHASE ; 2 = VR_PVPP_DEF_SNUB
C7A36  CAP_A  22.0UF 4V 20% X6S  pkg 0603V  page 132 : 1 = PVNN_PCH_STBY ; 2 = GND
C7A37  CAP_A  1.0UF 6.3V 10% X6S  pkg 0402V  page 218 : 1 = VR_PVDDQ_DEF_VDD ; 2 = GND
C7A38  CAP_A  0.1UF 16V 10% X7R  pkg 0402V  page 218 : 1 = VR_PVDDQ_DEF_VDD ; 2 = GND
C7A39  CAP_A  0.1UF 16V 10% X7R  pkg 0402V  page 236 : 1 = VR_FET_SW_P12V_STBY_PVDDQ_DEF ; 2 = GND
C7A40  CAP_A  0.1UF 16V 10% X7R  pkg 0402V  page 236 : 1 = VR_FET_SW_P12V_STBY_PVDDQ_DEF ; 2 = GND
C7A41  CAP  0.22UF 16V 10% X7R  pkg 0402  page 236 : 1 = P5V_STBY ; 2 = GND
C7A42  CAP  22UF 4V 20% X6S  pkg 0805LF  page 236 : 1 = P1V05_PCH_STBY ; 2 = GND
C7A43  CAP  0.220UF 16V 10% X7R  pkg 0402  page 236 : 1 = VR_PVNN_PCH_PH1_BOOT ; 2 = VR_PVNN_PCH_PH1_PHASE
C7A44  CAP  0.220UF 16V 10% X7R  pkg 0402  page 236 : 1 = VR_P1V05_PCH_STBY_PH1_BOOT ; 2 = VR_P1V05_PCH_STBY_PH1_PHASE
C7B1  CAP_A  1.0UF 6.3V 10% X6S  pkg 0402V  page 218 : 1 = VR_PVDDQ_DEF_VD12 ; 2 = GND
C7B2  CAP_A  0.1UF 16V 10% X7R  pkg 0402V  page 218 : 1 = VR_PVDDQ_DEF_VD12 ; 2 = GND
C7B3  CAP  1000PF 50V 10% X7R  pkg 0402LF  page 218 : 1 = PWRGD_PVDDQ_DEF_R ; 2 = GND
C7B4  CAP  47UF 4V 20% X6S  pkg 0805  page 132 : 1 = PVNN_PCH_STBY ; 2 = GND
C7B5  CAP  10UF 16V 10% X6S  pkg 0805  page 232 : 1 = VR_FET_SW_P12V_STBY_PVPP_DEF ; 2 = GND
C7B6  CAP_A  0.1UF 16V 10% X7R  pkg 0402V  page 232 : 1 = VR_FET_SW_P12V_STBY_PVPP_DEF ; 2 = GND
C7B7  CAP  47UF 4V 20% X6S  pkg 0805  page 232 : 1 = PVPP_DEF ; 2 = GND
C7B8  SC22U16V5MX-4-GP  20%  pkg SMD-BCG5  page 232 : 1 = VR_FET_SW_P12V_STBY_PVPP_DEF ; 2 = GND
C7B9  CAP  1000PF 50V 10% EMPTY  pkg 0402LF  page 232 : 1 = FM_PVPP_CPU0_EN ; 2 = AGND_PVPP_DEF
C7B10  CAP  100.0PF 50V 5% COG  pkg 0402LF  page 232 : 1 = VR_FB_PVPP_DEF ; 2 = VR_COMP_PVPP_DEF_3
C7B11  CAP  0.027UF 16V 10% X7R  pkg 0402  page 232 : 1 = VR_PVPP_DEF_SS ; 2 = AGND_PVPP_DEF
C7B12  CAP  1000PF 50V 10% X7R  pkg 0402LF  page 232 : 1 = PWRGD_PVPP_DEF_R ; 2 = GND
C7B13  CAP  2200PF 50V 10% X7R  pkg 0402LF  page 232 : 1 = VR_COMP_PVPP_DEF ; 2 = VR_FB_PVPP_DEF
C7B14  CAP  2200PF 50V 10% X7R  pkg 0402LF  page 232 : 1 = VR_COMP_RC_PVPP_DEF ; 2 = VR_COMP_PVPP_DEF_3
C7B15  CAP_A  22.0UF 4V 20% X6S  pkg 0603V  page 131 : 1 = P1V05_PCH_STBY ; 2 = GND
C7B16  CAP_A  22.0UF 4V 20% X6S  pkg 0603V  page 131 : 1 = P1V05_PCH_STBY ; 2 = GND
C7B17  CAP_A  22.0UF 4V 20% X6S  pkg 0603V  page 131 : 1 = P1V05_PCH_STBY ; 2 = GND
C7B18  CAP_A  22.0UF 4V 20% X6S  pkg 0603V  page 131 : 1 = P1V05_PCH_STBY ; 2 = GND
C7B19  CAP_A  22.0UF 4V 20% X6S  pkg 0603V  page 131 : 1 = P1V05_PCH_STBY ; 2 = GND
C7B20  CAP_A  22.0UF 4V 20% X6S  pkg 0603V  page 131 : 1 = P1V05_PCH_STBY ; 2 = GND
C7B21  CAP_A  22.0UF 4V 20% X6S  pkg 0603V  page 131 : 1 = P1V05_PCH_STBY ; 2 = GND
C7B22  CAP_A  22.0UF 4V 20% X6S  pkg 0603V  page 131 : 1 = P1V05_PCH_STBY ; 2 = GND
C7B23  CAP_A  22.0UF 4V 20% X6S  pkg 0603V  page 131 : 1 = P1V05_PCH_STBY ; 2 = GND
C7B24  CAP_A  22.0UF 4V 20% X6S  pkg 0603V  page 131 : 1 = P1V05_PCH_STBY ; 2 = GND
C7B25  CAP  0.22UF 16V 10% X7R  pkg 0402  page 129 : 1 = DMI_CPU0_PCH_TX_DP<3> ; 2 = DMI_CPU0_PCH_TX_C_DP<3>
C7B26  CAP  0.22UF 16V 10% X7R  pkg 0402  page 129 : 1 = DMI_CPU0_PCH_TX_DN<3> ; 2 = DMI_CPU0_PCH_TX_C_DN<3>
C7B27  CAP  0.22UF 16V 10% X7R  pkg 0402  page 129 : 1 = DMI_CPU0_PCH_TX_DP<2> ; 2 = DMI_CPU0_PCH_TX_C_DP<2>
C7B28  CAP  0.22UF 16V 10% X7R  pkg 0402  page 129 : 1 = DMI_CPU0_PCH_TX_DP<1> ; 2 = DMI_CPU0_PCH_TX_C_DP<1>
C7B29  CAP  0.22UF 16V 10% X7R  pkg 0402  page 129 : 1 = DMI_CPU0_PCH_TX_DN<2> ; 2 = DMI_CPU0_PCH_TX_C_DN<2>
C7B30  CAP  0.1UF 25V 10% X7R  pkg 0603LF  page 232 : 1 = VR_PVPP_DEF_PHASE ; 2 = VR_PVPP_DEF_BOOT_R
C7C1  CAP  0.22UF 16V 10% X7R  pkg 0402  page 129 : 1 = DMI_CPU0_PCH_TX_DN<1> ; 2 = DMI_CPU0_PCH_TX_C_DN<1>
C7C2  CAP  0.22UF 16V 10% X7R  pkg 0402  page 129 : 1 = DMI_CPU0_PCH_TX_DP<0> ; 2 = DMI_CPU0_PCH_TX_C_DP<0>
C7C3  CAP  0.22UF 16V 10% X7R  pkg 0402  page 129 : 1 = DMI_CPU0_PCH_TX_DN<0> ; 2 = DMI_CPU0_PCH_TX_C_DN<0>
C7C4  CAP  15.0PF 50V 5% COG  pkg 0402LF  page 114 : 1 = XTAL_PCH_48M_IN ; 2 = GND
C7C5  CAP  15.0PF 50V 5% COG  pkg 0402LF  page 114 : 1 = XTAL_PCH_48M_OUT ; 2 = GND
C7C6  CAP_A  22.0UF 4V 20% X6S  pkg 0603V  page 212 : 1 = PVCCIO_CPU0 ; 2 = GND
C7C7  SC22U16V5MX-4-GP  20%  pkg SMD-BCG5  page 212 : 1 = VR_FET_SW_P12V_STBY_PVCCIO_CPU0 ; 2 = GND
C7C8  SC22U16V5MX-4-GP  20%  pkg SMD-BCG5  page 212 : 1 = VR_FET_SW_P12V_STBY_PVCCIO_CPU0 ; 2 = GND
C7C9  CAP_A  22.0UF 4V 20% X6S  pkg 0603V  page 132 : 1 = PVNN_PCH_STBY ; 2 = GND
C7C10  CAP_A  22.0UF 4V 20% X6S  pkg 0603V  page 212 : 1 = PVCCIO_CPU0 ; 2 = GND
C7C11  CAP_A  0.1UF 16V 10% X7R  pkg 0402V  page 212 : 1 = VR_FET_SW_P12V_STBY_PVCCIO_CPU0 ; 2 = GND
C7C12  CAP  1.0UF 16V 10% X6S  pkg 0402  page 212 : 1 = VR_FET_SW_P12V_STBY_PVCCIO_CPU0 ; 2 = GND
C7C13  CAP  15.0PF 50V 5% COG  pkg 0402LF  page 114 : 1 = XTAL_33K_RTC1 ; 2 = GND
C7C14  CAP  0.220UF 16V 10% X7R  pkg 0402  page 212 : 1 = VR_PVCCIO_CPU0_PH1_BOOT ; 2 = VR_PVCCIO_CPU0_PH1_PHASE
C7C15  CAP  15.0PF 50V 5% COG  pkg 0402LF  page 114 : 1 = XTAL_33K_RTC2 ; 2 = GND
C7C17  CAP  1.0UF 16V 10% X6S  pkg 0402  page 212 : 1 = VR_PVCCIO_CPU0_PH1_VCIN ; 2 = GND
C7C18  CAP  0.22UF 16V 10% X7R  pkg 0402  page 212 : 1 = P5V_STBY ; 2 = GND
C7C19  CAP_A  1.0UF 6.3V 10% X6S  pkg 0402V  page 137 : 1 = RST_RTCRST_N ; 2 = GND
C7C20  SC1U10V2KX-4-GP  10%  pkg SMD-BCG6  page 212 : 1 = P5V_STBY ; 2 = GND
C7D1  CAP_A  0.1UF 16V 10% X7R  pkg 0402V  page 118 : 1 = P3V3_STBY ; 2 = GND
C7D2  CAP  10UF 6.3V 20% X6S  pkg 0603  page 130 : 1 = P3V3_STBY ; 2 = GND
C7D3  CAP_A  22.0UF 4V 20% X6S  pkg 0603V  page 130 : 1 = P1V8_PCH_STBY ; 2 = GND
C7D4  CAP  1.0UF 16V 10% X6S  pkg 0402  page 92 : 1 = P3V3 ; 2 = GND
C7D5  CAP_A  0.1UF 16V 10% X7R  pkg 0402V  page 92 : 1 = P0V7_GTL2104_VREF_0 ; 2 = GND
C7E1  CAP_A  0.1UF 16V 10% X7R  pkg 0402V  page 99 : 1 = PVCCIO_CPU0 ; 2 = GND
C7E2  CAP_A  0.1UF 16V 10% X7R  pkg 0402V  page 99 : 1 = PVPP_DEF ; 2 = GND
C7E3  CAP_A  0.1UF 16V 10% X7R  pkg 0402V  page 95 : 1 = P3V3_STBY ; 2 = GND
C7E4  CAP_A  0.1UF 16V 10% X7R  pkg 0402V  page 95 : 1 = P3V3_STBY ; 2 = GND
C7E5  CAP_A  0.1UF 16V 10% X7R  pkg 0402V  page 198 : 1 = P12V_STBY ; 2 = GND
C7E6  CAP  10UF 16V 10% X6S  pkg 0805  page 198 : 1 = P12V_STBY ; 2 = GND
C7E8  CAP  10UF 16V 10% X6S  pkg 0805  page 198 : 1 = P12V ; 2 = GND
C7E9  CAP_A  0.1UF 16V 10% X7R  pkg 0402V  page 198 : 1 = P12V ; 2 = GND
C7E10  CAP  1000PF 50V 10% X7R  pkg 0402LF  page 241 : 1 = PWRGD_P5V_STBY_R ; 2 = GND
C7E11  CAP  22UF 16V 10% X6S  pkg 1206LF  page 241 : 1 = VR_FET_SW_P5V_STBY_PVIN ; 2 = GND
C7E12  SC22U16V5MX-4-GP  20%  pkg SMD-BCG5  page 241 : 1 = VR_FET_SW_P5V_STBY_PVIN ; 2 = GND
C7E13  SC22U16V5MX-4-GP  20%  pkg SMD-BCG5  page 241 : 1 = VR_FET_SW_P5V_STBY_PVIN ; 2 = GND
C7E14  CAP  1.0UF 16V 10% X6S  pkg 0402  page 241 : 1 = VR_P5V_STBY_VIN ; 2 = GND
C7F1  CAP_A  0.01UF 25V 10% X7R  pkg 0402V  page 153 : 1 = P3V3_STBY ; 2 = GND
C7F2  CAP_A  1.0UF 6.3V 10% X6S  pkg 0402V  page 153 : 1 = P3V3_STBY ; 2 = GND
C7F3  CAP  3300PF 50V 10% EMPTY  pkg 0402LF  page 231 : 1 = VR_PVPP_ABC_PHASE ; 2 = VR_PVPP_ABC_SNUB
C7F4  CAP  0.1UF 25V 10% X7R  pkg 0603LF  page 231 : 1 = VR_PVPP_ABC_PHASE ; 2 = VR_PVPP_ABC_BOOT_R
